(kicad_pcb
	(version 20241229)
	(generator "pcbnew")
	(generator_version "9.0")
	(general
		(thickness 1.599998)
		(legacy_teardrops no)
	)
	(paper "A4")
	(title_block
		(date "2023-02-12")
		(rev "1.1.5")
		(comment 9 "footprints 1-2 of 473")
	)
	(layers
		(0 "F.Cu" signal)
		(4 "In1.Cu" power "In1.GND")
		(6 "In2.Cu" signal)
		(8 "In3.Cu" power "In3.GND")
		(10 "In4.Cu" power "In4.VCC")
		(12 "In5.Cu" signal)
		(14 "In6.Cu" power "In6.VCC")
		(2 "B.Cu" signal)
		(9 "F.Adhes" user "F.Adhesive")
		(11 "B.Adhes" user "B.Adhesive")
		(13 "F.Paste" user)
		(15 "B.Paste" user)
		(5 "F.SilkS" user "F.Silkscreen")
		(7 "B.SilkS" user "B.Silkscreen")
		(1 "F.Mask" user)
		(3 "B.Mask" user)
		(17 "Dwgs.User" user "User.Drawings")
		(19 "Cmts.User" user "User.Comments")
		(21 "Eco1.User" user "User.Eco1")
		(23 "Eco2.User" user "User.Eco2")
		(25 "Edge.Cuts" user)
		(27 "Margin" user)
		(31 "F.CrtYd" user "F.Courtyard")
		(29 "B.CrtYd" user "B.Courtyard")
		(35 "F.Fab" user)
		(33 "B.Fab" user)
	)
	(footprint "antmicro-footprints:C_0402_1005Metric"
		(layer "F.Cu")
		(at 180.1885 115.731 180)
		(descr "Capacitor SMD 0402")
		(tags "capacitor SMD 0402")
		(property "Reference" "C22"
			(at -0.8115 -0.369 180)
			(layer "F.SilkS")
			(effects
				(font
					(size 0.7 0.7)
					(thickness 0.15)
				)
				(justify left bottom)
			)
		)
		(property "Value" "C_100n_6V3_0402"
			(at 0 1.4 180)
			(layer "F.Fab")
			(effects
				(font
					(size 0.7 0.7)
					(thickness 0.15)
				)
				(justify left bottom)
			)
		)
		(property "Description" " "
			(at 0 0 180)
			(layer "F.Fab")
			(hide yes)
			(effects
				(font
					(size 1.27 1.27)
					(thickness 0.15)
				)
			)
		)
		(property "Author" "Antmicro"
			(at 360.377 231.462 0)
			(layer "F.Fab")
			(hide yes)
			(effects
				(font
					(size 1 1)
					(thickness 0.15)
				)
			)
		)
		(property "Dielectric" ""
			(at 360.377 231.462 0)
			(layer "F.Fab")
			(hide yes)
			(effects
				(font
					(size 1 1)
					(thickness 0.15)
				)
			)
		)
		(property "License" "Apache-2.0"
			(at 360.377 231.462 0)
			(layer "F.Fab")
			(hide yes)
			(effects
				(font
					(size 1 1)
					(thickness 0.15)
				)
			)
		)
		(property "MPN" "0402X104K6R3CT"
			(at 360.377 231.462 0)
			(layer "F.Fab")
			(hide yes)
			(effects
				(font
					(size 1 1)
					(thickness 0.15)
				)
			)
		)
		(property "Manufacturer" "Walsin"
			(at 360.377 231.462 0)
			(layer "F.Fab")
			(hide yes)
			(effects
				(font
					(size 1 1)
					(thickness 0.15)
				)
			)
		)
		(property "Val" "100n"
			(at 360.377 231.462 0)
			(layer "F.Fab")
			(hide yes)
			(effects
				(font
					(size 1 1)
					(thickness 0.15)
				)
			)
		)
		(property "Voltage" ""
			(at 360.377 231.462 0)
			(layer "F.Fab")
			(hide yes)
			(effects
				(font
					(size 1 1)
					(thickness 0.15)
				)
			)
		)
		(sheetname "Config SPI flash")
		(sheetfile "config-spi.kicad_sch")
		(attr smd)
		(fp_rect
			(start -0.94 -0.47)
			(end 0.94 0.47)
			(stroke
				(width 0.05)
				(type solid)
			)
			(fill no)
			(layer "F.CrtYd")
		)
		(fp_rect
			(start -0.499 -0.249)
			(end 0.499 0.249)
			(stroke
				(width 0.15)
				(type solid)
			)
			(fill no)
			(layer "F.Fab")
		)
		(pad "1" smd roundrect
			(at -0.484 0 180)
			(size 0.59 0.64)
			(layers "F.Cu" "F.Mask" "F.Paste")
			(roundrect_rratio 0.25)
			(net 5 "GND")
			(pintype "passive")
		)
		(pad "2" smd roundrect
			(at 0.484 0 180)
			(size 0.59 0.64)
			(layers "F.Cu" "F.Mask" "F.Paste")
			(roundrect_rratio 0.25)
			(net 459 "3V3_SYS")
			(pintype "passive")
		)
	)
	(footprint "antmicro-footprints:R_0402_1005Metric"
		(layer "F.Cu")
		(at 157.094 113.05 -90)
		(descr "Resistor SMD 0402")
		(tags "resistor SMD 0402")
		(property "Reference" "R43"
			(at -0.835 -0.416 270)
			(layer "F.SilkS")
			(effects
				(font
					(size 0.7 0.7)
					(thickness 0.15)
				)
				(justify left bottom)
			)
		)
		(property "Value" "R_0R_0402"
			(at 0 1.4 270)
			(layer "F.Fab")
			(effects
				(font
					(size 0.7 0.7)
					(thickness 0.15)
				)
				(justify left bottom)
			)
		)
		(property "Description" "0R resistor in 0402 package with unspecified tolerance"
			(at 0 0 270)
			(layer "F.Fab")
			(hide yes)
			(effects
				(font
					(size 1.27 1.27)
					(thickness 0.15)
				)
			)
		)
		(property "Author" "Antmicro"
			(at 44.044 270.144 0)
			(layer "F.Fab")
			(hide yes)
			(effects
				(font
					(size 1 1)
					(thickness 0.15)
				)
			)
		)
		(property "Current" "1A"
			(at 44.044 270.144 0)
			(layer "F.Fab")
			(hide yes)
			(effects
				(font
					(size 1 1)
					(thickness 0.15)
				)
			)
		)
		(property "License" "Apache-2.0"
			(at 44.044 270.144 0)
			(layer "F.Fab")
			(hide yes)
			(effects
				(font
					(size 1 1)
					(thickness 0.15)
				)
			)
		)
		(property "MPN" "ERJ2GE0R00X"
			(at 44.044 270.144 0)
			(layer "F.Fab")
			(hide yes)
			(effects
				(font
					(size 1 1)
					(thickness 0.15)
				)
			)
		)
		(property "Manufacturer" "Panasonic"
			(at 44.044 270.144 0)
			(layer "F.Fab")
			(hide yes)
			(effects
				(font
					(size 1 1)
					(thickness 0.15)
				)
			)
		)
		(property "Tolerance" ""
			(at 44.044 270.144 0)
			(layer "F.Fab")
			(hide yes)
			(effects
				(font
					(size 1 1)
					(thickness 0.15)
				)
			)
		)
		(property "Val" "0R"
			(at 44.044 270.144 0)
			(layer "F.Fab")
			(hide yes)
			(effects
				(font
					(size 1 1)
					(thickness 0.15)
				)
			)
		)
		(sheetname "Interfaces")
		(sheetfile "interfaces.kicad_sch")
		(attr smd)
		(fp_rect
			(start -0.93 -0.47)
			(end 0.93 0.47)
			(stroke
				(width 0.05)
				(type solid)
			)
			(fill no)
			(layer "F.CrtYd")
		)
		(fp_rect
			(start -0.5 -0.25)
			(end 0.5 0.25)
			(stroke
				(width 0.15)
				(type solid)
			)
			(fill no)
			(layer "F.Fab")
		)
		(pad "1" smd roundrect
			(at -0.485 0 270)
			(size 0.59 0.64)
			(layers "F.Cu" "F.Mask" "F.Paste")
			(roundrect_rratio 0.25)
			(net 49 "TMDS_D1_N")
			(pintype "passive")
		)
		(pad "2" smd roundrect
			(at 0.485 0 270)
			(size 0.59 0.64)
			(layers "F.Cu" "F.Mask" "F.Paste")
			(roundrect_rratio 0.25)
			(net 667 "/Interfaces/C_TMDS_D1_N")
			(pintype "passive")
		)
	)
)
